(kicad_pcb
	(version 20241229)
	(generator "pcbnew")
	(generator_version "9.0")
	(general
		(thickness 1.61)
		(legacy_teardrops no)
	)
	(paper "A3")
	(title_block
		(title "SO-DIMM DDR5 Tester")
		(date "2025-11-26")
		(rev "1.3.0")
		(comment 9 "footprints 331-337 of 627")
	)
	(layers
		(0 "F.Cu" signal)
		(4 "In1.Cu" power)
		(6 "In2.Cu" mixed)
		(8 "In3.Cu" power)
		(10 "In4.Cu" mixed)
		(12 "In5.Cu" power)
		(14 "In6.Cu" mixed)
		(16 "In7.Cu" power)
		(18 "In8.Cu" power)
		(20 "In9.Cu" mixed)
		(22 "In10.Cu" power)
		(2 "B.Cu" signal)
		(9 "F.Adhes" user "F.Adhesive")
		(11 "B.Adhes" user "B.Adhesive")
		(13 "F.Paste" user)
		(15 "B.Paste" user)
		(5 "F.SilkS" user "F.Silkscreen")
		(7 "B.SilkS" user "B.Silkscreen")
		(1 "F.Mask" user)
		(3 "B.Mask" user)
		(17 "Dwgs.User" user "User.Drawings")
		(19 "Cmts.User" user "User.Comments")
		(21 "Eco1.User" user "User.Eco1")
		(23 "Eco2.User" user "User.Eco2")
		(25 "Edge.Cuts" user)
		(27 "Margin" user)
		(31 "F.CrtYd" user "F.Courtyard")
		(29 "B.CrtYd" user "B.Courtyard")
		(35 "F.Fab" user)
		(33 "B.Fab" user)
	)
	(footprint "antmicro-footprints:R_0402_1005Metric"
		(layer "B.Cu")
		(at 84.75 174.4)
		(descr "Resistor SMD 0402")
		(tags "resistor SMD 0402")
		(property "Reference" "R87"
			(at -1.122484 0.772697 180)
			(layer "B.SilkS")
			(hide yes)
			(effects
				(font
					(size 0.7 0.7)
					(thickness 0.15)
				)
				(justify left bottom mirror)
			)
		)
		(property "Value" "R_20k_0402"
			(at -1.011843 -1.772047 180)
			(layer "B.Fab")
			(effects
				(font
					(size 0.7 0.7)
					(thickness 0.15)
				)
				(justify left bottom mirror)
			)
		)
		(property "Datasheet" "https://www.bourns.com/docs/product-datasheets/cr.pdf"
			(at 0 0 0)
			(layer "F.Fab")
			(hide yes)
			(effects
				(font
					(size 1.27 1.27)
					(thickness 0.15)
				)
			)
		)
		(property "Author" "Antmicro"
			(at 0 0 0)
			(layer "B.Fab")
			(hide yes)
			(effects
				(font
					(size 1 1)
					(thickness 0.15)
				)
				(justify mirror)
			)
		)
		(property "License" "Apache-2.0"
			(at 0 0 0)
			(layer "B.Fab")
			(hide yes)
			(effects
				(font
					(size 1 1)
					(thickness 0.15)
				)
				(justify mirror)
			)
		)
		(property "MPN" "CR0402-FX-2002GLF"
			(at 0 0 0)
			(layer "B.Fab")
			(hide yes)
			(effects
				(font
					(size 1 1)
					(thickness 0.15)
				)
				(justify mirror)
			)
		)
		(property "Manufacturer" "Bourns"
			(at 0 0 0)
			(layer "B.Fab")
			(hide yes)
			(effects
				(font
					(size 1 1)
					(thickness 0.15)
				)
				(justify mirror)
			)
		)
		(property "Tolerance" "1%"
			(at 0 0 0)
			(layer "B.Fab")
			(hide yes)
			(effects
				(font
					(size 1 1)
					(thickness 0.15)
				)
				(justify mirror)
			)
		)
		(property "Val" "20k"
			(at 0 0 0)
			(layer "B.Fab")
			(hide yes)
			(effects
				(font
					(size 1 1)
					(thickness 0.15)
				)
				(justify mirror)
			)
		)
		(sheetname "/HDMI + SD Card/")
		(sheetfile "hdmi-sd-card.kicad_sch")
		(attr smd)
		(fp_rect
			(start -0.93 0.47)
			(end 0.93 -0.47)
			(stroke
				(width 0.05)
				(type solid)
			)
			(fill no)
			(layer "B.CrtYd")
		)
		(fp_rect
			(start -0.5 0.25)
			(end 0.5 -0.25)
			(stroke
				(width 0.15)
				(type solid)
			)
			(fill no)
			(layer "B.Fab")
		)
		(pad "1" smd roundrect
			(at -0.485 0)
			(size 0.59 0.64)
			(layers "B.Cu" "B.Mask" "B.Paste")
			(roundrect_rratio 0.25)
			(net 200 "+3V3")
			(pintype "passive")
		)
		(pad "2" smd roundrect
			(at 0.485 0)
			(size 0.59 0.64)
			(layers "B.Cu" "B.Mask" "B.Paste")
			(roundrect_rratio 0.25)
			(net 350 "/FPGA bank 16/SD.DAT2")
			(pintype "passive")
		)
	)
	(footprint "antmicro-footprints:R_0402_1005Metric"
		(layer "B.Cu")
		(at 99.500501 161.576 90)
		(descr "Resistor SMD 0402")
		(tags "resistor SMD 0402")
		(property "Reference" "R101"
			(at -1.122484 0.772697 270)
			(layer "B.SilkS")
			(hide yes)
			(effects
				(font
					(size 0.7 0.7)
					(thickness 0.15)
				)
				(justify left bottom mirror)
			)
		)
		(property "Value" "R_10k_0402"
			(at -1.011843 -1.772047 270)
			(layer "B.Fab")
			(effects
				(font
					(size 0.7 0.7)
					(thickness 0.15)
				)
				(justify left bottom mirror)
			)
		)
		(property "Datasheet" "https://www.bourns.com/docs/product-datasheets/cr.pdf"
			(at 0 0 90)
			(layer "F.Fab")
			(hide yes)
			(effects
				(font
					(size 1.27 1.27)
					(thickness 0.15)
				)
			)
		)
		(property "Author" "Antmicro"
			(at 261.076501 62.075499 0)
			(layer "B.Fab")
			(hide yes)
			(effects
				(font
					(size 1 1)
					(thickness 0.15)
				)
				(justify mirror)
			)
		)
		(property "License" "Apache-2.0"
			(at 261.076501 62.075499 0)
			(layer "B.Fab")
			(hide yes)
			(effects
				(font
					(size 1 1)
					(thickness 0.15)
				)
				(justify mirror)
			)
		)
		(property "MPN" "CR0402-FX-1002GLF"
			(at 261.076501 62.075499 0)
			(layer "B.Fab")
			(hide yes)
			(effects
				(font
					(size 1 1)
					(thickness 0.15)
				)
				(justify mirror)
			)
		)
		(property "Manufacturer" "Bourns"
			(at 261.076501 62.075499 0)
			(layer "B.Fab")
			(hide yes)
			(effects
				(font
					(size 1 1)
					(thickness 0.15)
				)
				(justify mirror)
			)
		)
		(property "Tolerance" "1%"
			(at 261.076501 62.075499 0)
			(layer "B.Fab")
			(hide yes)
			(effects
				(font
					(size 1 1)
					(thickness 0.15)
				)
				(justify mirror)
			)
		)
		(property "Val" "10k"
			(at 261.076501 62.075499 0)
			(layer "B.Fab")
			(hide yes)
			(effects
				(font
					(size 1 1)
					(thickness 0.15)
				)
				(justify mirror)
			)
		)
		(sheetname "/Ethernet/")
		(sheetfile "ethernet.kicad_sch")
		(attr exclude_from_pos_files exclude_from_bom dnp)
		(fp_rect
			(start -0.93 0.47)
			(end 0.93 -0.47)
			(stroke
				(width 0.05)
				(type solid)
			)
			(fill no)
			(layer "B.CrtYd")
		)
		(fp_rect
			(start -0.5 0.25)
			(end 0.5 -0.25)
			(stroke
				(width 0.15)
				(type solid)
			)
			(fill no)
			(layer "B.Fab")
		)
		(pad "1" smd roundrect
			(at -0.485 0 90)
			(size 0.59 0.64)
			(layers "B.Cu" "B.Mask" "B.Paste")
			(roundrect_rratio 0.25)
			(net 673 "/Ethernet/ETH.RXD0")
			(pintype "passive")
		)
		(pad "2" smd roundrect
			(at 0.485 0 90)
			(size 0.59 0.64)
			(layers "B.Cu" "B.Mask" "B.Paste")
			(roundrect_rratio 0.25)
			(net 200 "+3V3")
			(pintype "passive")
		)
	)
	(footprint "antmicro-footprints:R_0402_1005Metric"
		(layer "B.Cu")
		(at 98.450501 161.576 90)
		(descr "Resistor SMD 0402")
		(tags "resistor SMD 0402")
		(property "Reference" "R102"
			(at -1.122484 0.772697 270)
			(layer "B.SilkS")
			(hide yes)
			(effects
				(font
					(size 0.7 0.7)
					(thickness 0.15)
				)
				(justify left bottom mirror)
			)
		)
		(property "Value" "R_10k_0402"
			(at -1.011843 -1.772047 270)
			(layer "B.Fab")
			(effects
				(font
					(size 0.7 0.7)
					(thickness 0.15)
				)
				(justify left bottom mirror)
			)
		)
		(property "Datasheet" "https://www.bourns.com/docs/product-datasheets/cr.pdf"
			(at 0 0 90)
			(layer "F.Fab")
			(hide yes)
			(effects
				(font
					(size 1.27 1.27)
					(thickness 0.15)
				)
			)
		)
		(property "Author" "Antmicro"
			(at 260.026501 63.125499 0)
			(layer "B.Fab")
			(hide yes)
			(effects
				(font
					(size 1 1)
					(thickness 0.15)
				)
				(justify mirror)
			)
		)
		(property "License" "Apache-2.0"
			(at 260.026501 63.125499 0)
			(layer "B.Fab")
			(hide yes)
			(effects
				(font
					(size 1 1)
					(thickness 0.15)
				)
				(justify mirror)
			)
		)
		(property "MPN" "CR0402-FX-1002GLF"
			(at 260.026501 63.125499 0)
			(layer "B.Fab")
			(hide yes)
			(effects
				(font
					(size 1 1)
					(thickness 0.15)
				)
				(justify mirror)
			)
		)
		(property "Manufacturer" "Bourns"
			(at 260.026501 63.125499 0)
			(layer "B.Fab")
			(hide yes)
			(effects
				(font
					(size 1 1)
					(thickness 0.15)
				)
				(justify mirror)
			)
		)
		(property "Tolerance" "1%"
			(at 260.026501 63.125499 0)
			(layer "B.Fab")
			(hide yes)
			(effects
				(font
					(size 1 1)
					(thickness 0.15)
				)
				(justify mirror)
			)
		)
		(property "Val" "10k"
			(at 260.026501 63.125499 0)
			(layer "B.Fab")
			(hide yes)
			(effects
				(font
					(size 1 1)
					(thickness 0.15)
				)
				(justify mirror)
			)
		)
		(sheetname "/Ethernet/")
		(sheetfile "ethernet.kicad_sch")
		(attr exclude_from_pos_files exclude_from_bom dnp)
		(fp_rect
			(start -0.93 0.47)
			(end 0.93 -0.47)
			(stroke
				(width 0.05)
				(type solid)
			)
			(fill no)
			(layer "B.CrtYd")
		)
		(fp_rect
			(start -0.5 0.25)
			(end 0.5 -0.25)
			(stroke
				(width 0.15)
				(type solid)
			)
			(fill no)
			(layer "B.Fab")
		)
		(pad "1" smd roundrect
			(at -0.485 0 90)
			(size 0.59 0.64)
			(layers "B.Cu" "B.Mask" "B.Paste")
			(roundrect_rratio 0.25)
			(net 674 "/Ethernet/ETH.RXD1")
			(pintype "passive")
		)
		(pad "2" smd roundrect
			(at 0.485 0 90)
			(size 0.59 0.64)
			(layers "B.Cu" "B.Mask" "B.Paste")
			(roundrect_rratio 0.25)
			(net 200 "+3V3")
			(pintype "passive")
		)
	)
	(footprint "antmicro-footprints:R_0402_1005Metric"
		(layer "B.Cu")
		(at 101.625501 161.601 90)
		(descr "Resistor SMD 0402")
		(tags "resistor SMD 0402")
		(property "Reference" "R105"
			(at -1.122484 0.772697 270)
			(layer "B.SilkS")
			(hide yes)
			(effects
				(font
					(size 0.7 0.7)
					(thickness 0.15)
				)
				(justify left bottom mirror)
			)
		)
		(property "Value" "R_10k_0402"
			(at -1.011843 -1.772047 270)
			(layer "B.Fab")
			(effects
				(font
					(size 0.7 0.7)
					(thickness 0.15)
				)
				(justify left bottom mirror)
			)
		)
		(property "Datasheet" "https://www.bourns.com/docs/product-datasheets/cr.pdf"
			(at 0 0 90)
			(layer "F.Fab")
			(hide yes)
			(effects
				(font
					(size 1.27 1.27)
					(thickness 0.15)
				)
			)
		)
		(property "Author" "Antmicro"
			(at 263.226501 59.975499 0)
			(layer "B.Fab")
			(hide yes)
			(effects
				(font
					(size 1 1)
					(thickness 0.15)
				)
				(justify mirror)
			)
		)
		(property "License" "Apache-2.0"
			(at 263.226501 59.975499 0)
			(layer "B.Fab")
			(hide yes)
			(effects
				(font
					(size 1 1)
					(thickness 0.15)
				)
				(justify mirror)
			)
		)
		(property "MPN" "CR0402-FX-1002GLF"
			(at 263.226501 59.975499 0)
			(layer "B.Fab")
			(hide yes)
			(effects
				(font
					(size 1 1)
					(thickness 0.15)
				)
				(justify mirror)
			)
		)
		(property "Manufacturer" "Bourns"
			(at 263.226501 59.975499 0)
			(layer "B.Fab")
			(hide yes)
			(effects
				(font
					(size 1 1)
					(thickness 0.15)
				)
				(justify mirror)
			)
		)
		(property "Tolerance" "1%"
			(at 263.226501 59.975499 0)
			(layer "B.Fab")
			(hide yes)
			(effects
				(font
					(size 1 1)
					(thickness 0.15)
				)
				(justify mirror)
			)
		)
		(property "Val" "10k"
			(at 263.226501 59.975499 0)
			(layer "B.Fab")
			(hide yes)
			(effects
				(font
					(size 1 1)
					(thickness 0.15)
				)
				(justify mirror)
			)
		)
		(sheetname "/Ethernet/")
		(sheetfile "ethernet.kicad_sch")
		(attr exclude_from_pos_files exclude_from_bom dnp)
		(fp_rect
			(start -0.93 0.47)
			(end 0.93 -0.47)
			(stroke
				(width 0.05)
				(type solid)
			)
			(fill no)
			(layer "B.CrtYd")
		)
		(fp_rect
			(start -0.5 0.25)
			(end 0.5 -0.25)
			(stroke
				(width 0.15)
				(type solid)
			)
			(fill no)
			(layer "B.Fab")
		)
		(pad "1" smd roundrect
			(at -0.485 0 90)
			(size 0.59 0.64)
			(layers "B.Cu" "B.Mask" "B.Paste")
			(roundrect_rratio 0.25)
			(net 677 "/Ethernet/ETH.RX_CTL")
			(pintype "passive")
		)
		(pad "2" smd roundrect
			(at 0.485 0 90)
			(size 0.59 0.64)
			(layers "B.Cu" "B.Mask" "B.Paste")
			(roundrect_rratio 0.25)
			(net 200 "+3V3")
			(pintype "passive")
		)
	)
	(footprint "antmicro-footprints:R_0402_1005Metric"
		(layer "B.Cu")
		(at 100.525501 161.576 90)
		(descr "Resistor SMD 0402")
		(tags "resistor SMD 0402")
		(property "Reference" "R106"
			(at -1.122484 0.772697 270)
			(layer "B.SilkS")
			(hide yes)
			(effects
				(font
					(size 0.7 0.7)
					(thickness 0.15)
				)
				(justify left bottom mirror)
			)
		)
		(property "Value" "R_10k_0402"
			(at -1.011843 -1.772047 270)
			(layer "B.Fab")
			(effects
				(font
					(size 0.7 0.7)
					(thickness 0.15)
				)
				(justify left bottom mirror)
			)
		)
		(property "Datasheet" "https://www.bourns.com/docs/product-datasheets/cr.pdf"
			(at 0 0 90)
			(layer "F.Fab")
			(hide yes)
			(effects
				(font
					(size 1.27 1.27)
					(thickness 0.15)
				)
			)
		)
		(property "Author" "Antmicro"
			(at 262.101501 61.050499 0)
			(layer "B.Fab")
			(hide yes)
			(effects
				(font
					(size 1 1)
					(thickness 0.15)
				)
				(justify mirror)
			)
		)
		(property "License" "Apache-2.0"
			(at 262.101501 61.050499 0)
			(layer "B.Fab")
			(hide yes)
			(effects
				(font
					(size 1 1)
					(thickness 0.15)
				)
				(justify mirror)
			)
		)
		(property "MPN" "CR0402-FX-1002GLF"
			(at 262.101501 61.050499 0)
			(layer "B.Fab")
			(hide yes)
			(effects
				(font
					(size 1 1)
					(thickness 0.15)
				)
				(justify mirror)
			)
		)
		(property "Manufacturer" "Bourns"
			(at 262.101501 61.050499 0)
			(layer "B.Fab")
			(hide yes)
			(effects
				(font
					(size 1 1)
					(thickness 0.15)
				)
				(justify mirror)
			)
		)
		(property "Tolerance" "1%"
			(at 262.101501 61.050499 0)
			(layer "B.Fab")
			(hide yes)
			(effects
				(font
					(size 1 1)
					(thickness 0.15)
				)
				(justify mirror)
			)
		)
		(property "Val" "10k"
			(at 262.101501 61.050499 0)
			(layer "B.Fab")
			(hide yes)
			(effects
				(font
					(size 1 1)
					(thickness 0.15)
				)
				(justify mirror)
			)
		)
		(sheetname "/Ethernet/")
		(sheetfile "ethernet.kicad_sch")
		(attr exclude_from_pos_files exclude_from_bom dnp)
		(fp_rect
			(start -0.93 0.47)
			(end 0.93 -0.47)
			(stroke
				(width 0.05)
				(type solid)
			)
			(fill no)
			(layer "B.CrtYd")
		)
		(fp_rect
			(start -0.5 0.25)
			(end 0.5 -0.25)
			(stroke
				(width 0.15)
				(type solid)
			)
			(fill no)
			(layer "B.Fab")
		)
		(pad "1" smd roundrect
			(at -0.485 0 90)
			(size 0.59 0.64)
			(layers "B.Cu" "B.Mask" "B.Paste")
			(roundrect_rratio 0.25)
			(net 678 "/Ethernet/ETH.RXC")
			(pintype "passive")
		)
		(pad "2" smd roundrect
			(at 0.485 0 90)
			(size 0.59 0.64)
			(layers "B.Cu" "B.Mask" "B.Paste")
			(roundrect_rratio 0.25)
			(net 200 "+3V3")
			(pintype "passive")
		)
	)
	(footprint "antmicro-footprints:R_0402_1005Metric"
		(layer "B.Cu")
		(at 95.308672 154.95 90)
		(descr "Resistor SMD 0402")
		(tags "resistor SMD 0402")
		(property "Reference" "R107"
			(at -1.122484 0.772697 270)
			(layer "B.SilkS")
			(hide yes)
			(effects
				(font
					(size 0.7 0.7)
					(thickness 0.15)
				)
				(justify left bottom mirror)
			)
		)
		(property "Value" "R_10k_0402"
			(at -1.011843 -1.772047 270)
			(layer "B.Fab")
			(effects
				(font
					(size 0.7 0.7)
					(thickness 0.15)
				)
				(justify left bottom mirror)
			)
		)
		(property "Datasheet" "https://www.bourns.com/docs/product-datasheets/cr.pdf"
			(at 0 0 90)
			(layer "F.Fab")
			(hide yes)
			(effects
				(font
					(size 1.27 1.27)
					(thickness 0.15)
				)
			)
		)
		(property "Author" "Antmicro"
			(at 250.258672 59.641328 0)
			(layer "B.Fab")
			(hide yes)
			(effects
				(font
					(size 1 1)
					(thickness 0.15)
				)
				(justify mirror)
			)
		)
		(property "License" "Apache-2.0"
			(at 250.258672 59.641328 0)
			(layer "B.Fab")
			(hide yes)
			(effects
				(font
					(size 1 1)
					(thickness 0.15)
				)
				(justify mirror)
			)
		)
		(property "MPN" "CR0402-FX-1002GLF"
			(at 250.258672 59.641328 0)
			(layer "B.Fab")
			(hide yes)
			(effects
				(font
					(size 1 1)
					(thickness 0.15)
				)
				(justify mirror)
			)
		)
		(property "Manufacturer" "Bourns"
			(at 250.258672 59.641328 0)
			(layer "B.Fab")
			(hide yes)
			(effects
				(font
					(size 1 1)
					(thickness 0.15)
				)
				(justify mirror)
			)
		)
		(property "Tolerance" "1%"
			(at 250.258672 59.641328 0)
			(layer "B.Fab")
			(hide yes)
			(effects
				(font
					(size 1 1)
					(thickness 0.15)
				)
				(justify mirror)
			)
		)
		(property "Val" "10k"
			(at 250.258672 59.641328 0)
			(layer "B.Fab")
			(hide yes)
			(effects
				(font
					(size 1 1)
					(thickness 0.15)
				)
				(justify mirror)
			)
		)
		(sheetname "/Ethernet/")
		(sheetfile "ethernet.kicad_sch")
		(attr smd)
		(fp_rect
			(start -0.93 0.47)
			(end 0.93 -0.47)
			(stroke
				(width 0.05)
				(type solid)
			)
			(fill no)
			(layer "B.CrtYd")
		)
		(fp_rect
			(start -0.5 0.25)
			(end 0.5 -0.25)
			(stroke
				(width 0.15)
				(type solid)
			)
			(fill no)
			(layer "B.Fab")
		)
		(pad "1" smd roundrect
			(at -0.485 0 90)
			(size 0.59 0.64)
			(layers "B.Cu" "B.Mask" "B.Paste")
			(roundrect_rratio 0.25)
			(net 679 "/Ethernet/ETH.REF_CLK")
			(pintype "passive")
		)
		(pad "2" smd roundrect
			(at 0.485 0 90)
			(size 0.59 0.64)
			(layers "B.Cu" "B.Mask" "B.Paste")
			(roundrect_rratio 0.25)
			(net 200 "+3V3")
			(pintype "passive")
		)
	)
	(footprint "antmicro-footprints:R_0402_1005Metric"
		(layer "B.Cu")
		(at 98.1 153.8)
		(descr "Resistor SMD 0402")
		(tags "resistor SMD 0402")
		(property "Reference" "R111"
			(at -1.122484 0.772697 180)
			(layer "B.SilkS")
			(hide yes)
			(effects
				(font
					(size 0.7 0.7)
					(thickness 0.15)
				)
				(justify left bottom mirror)
			)
		)
		(property "Value" "R_10k_0402"
			(at -1.011843 -1.772047 180)
			(layer "B.Fab")
			(effects
				(font
					(size 0.7 0.7)
					(thickness 0.15)
				)
				(justify left bottom mirror)
			)
		)
		(property "Datasheet" "https://www.bourns.com/docs/product-datasheets/cr.pdf"
			(at 0 0 0)
			(layer "F.Fab")
			(hide yes)
			(effects
				(font
					(size 1.27 1.27)
					(thickness 0.15)
				)
			)
		)
		(property "Author" "Antmicro"
			(at 0 0 0)
			(layer "B.Fab")
			(hide yes)
			(effects
				(font
					(size 1 1)
					(thickness 0.15)
				)
				(justify mirror)
			)
		)
		(property "License" "Apache-2.0"
			(at 0 0 0)
			(layer "B.Fab")
			(hide yes)
			(effects
				(font
					(size 1 1)
					(thickness 0.15)
				)
				(justify mirror)
			)
		)
		(property "MPN" "CR0402-FX-1002GLF"
			(at 0 0 0)
			(layer "B.Fab")
			(hide yes)
			(effects
				(font
					(size 1 1)
					(thickness 0.15)
				)
				(justify mirror)
			)
		)
		(property "Manufacturer" "Bourns"
			(at 0 0 0)
			(layer "B.Fab")
			(hide yes)
			(effects
				(font
					(size 1 1)
					(thickness 0.15)
				)
				(justify mirror)
			)
		)
		(property "Tolerance" "1%"
			(at 0 0 0)
			(layer "B.Fab")
			(hide yes)
			(effects
				(font
					(size 1 1)
					(thickness 0.15)
				)
				(justify mirror)
			)
		)
		(property "Val" "10k"
			(at 0 0 0)
			(layer "B.Fab")
			(hide yes)
			(effects
				(font
					(size 1 1)
					(thickness 0.15)
				)
				(justify mirror)
			)
		)
		(sheetname "/Ethernet/")
		(sheetfile "ethernet.kicad_sch")
		(attr smd)
		(fp_rect
			(start -0.93 0.47)
			(end 0.93 -0.47)
			(stroke
				(width 0.05)
				(type solid)
			)
			(fill no)
			(layer "B.CrtYd")
		)
		(fp_rect
			(start -0.5 0.25)
			(end 0.5 -0.25)
			(stroke
				(width 0.15)
				(type solid)
			)
			(fill no)
			(layer "B.Fab")
		)
		(pad "1" smd roundrect
			(at -0.485 0)
			(size 0.59 0.64)
			(layers "B.Cu" "B.Mask" "B.Paste")
			(roundrect_rratio 0.25)
			(net 681 "/Ethernet/ETH.~{RESET}")
			(pintype "passive")
		)
		(pad "2" smd roundrect
			(at 0.485 0)
			(size 0.59 0.64)
			(layers "B.Cu" "B.Mask" "B.Paste")
			(roundrect_rratio 0.25)
			(net 200 "+3V3")
			(pintype "passive")
		)
	)
)
